(kicad_pcb
	(version 20241229)
	(generator "pcbnew")
	(generator_version "9.0")
	(general
		(thickness 1.711)
		(legacy_teardrops no)
	)
	(paper "A4")
	(title_block
		(title "Antmicro Baseboard for Jetson AGX Thor")
		(date "2026-02-18")
		(rev "1.1.0")
		(company "Antmicro Ltd")
		(comment 1 "www.antmicro.com")
		(comment 9 "footprints 480-483 of 1170")
	)
	(layers
		(0 "F.Cu" signal)
		(4 "In1.Cu" signal)
		(6 "In2.Cu" signal)
		(8 "In3.Cu" signal)
		(10 "In4.Cu" jumper)
		(12 "In5.Cu" signal)
		(14 "In6.Cu" signal)
		(16 "In7.Cu" signal)
		(18 "In8.Cu" signal)
		(2 "B.Cu" signal)
		(9 "F.Adhes" user "F.Adhesive")
		(11 "B.Adhes" user "B.Adhesive")
		(13 "F.Paste" user)
		(15 "B.Paste" user)
		(5 "F.SilkS" user "F.Silkscreen")
		(7 "B.SilkS" user "B.Silkscreen")
		(1 "F.Mask" user)
		(3 "B.Mask" user)
		(17 "Dwgs.User" user "User.Drawings")
		(19 "Cmts.User" user "User.Comments")
		(21 "Eco1.User" user "User.Eco1")
		(23 "Eco2.User" user "User.Eco2")
		(25 "Edge.Cuts" user)
		(27 "Margin" user)
		(31 "F.CrtYd" user "F.Courtyard")
		(29 "B.CrtYd" user "B.Courtyard")
		(35 "F.Fab" user)
		(33 "B.Fab" user)
	)
	(footprint "antmicro-footprints:LED_0603_1608Metric_G"
		(layer "F.Cu")
		(at 164 55.3 -90)
		(descr "LED SMD 0603 Green")
		(tags "LED SMD 0603 Green")
		(property "Reference" "D43"
			(at -0.85 1.44 90)
			(layer "F.SilkS")
			(effects
				(font
					(size 0.7 0.7)
					(thickness 0.15)
				)
				(justify right top)
			)
		)
		(property "Value" "LED_G_0603_LTST-C190GKT"
			(at -0.001 1.599 90)
			(layer "F.Fab")
			(effects
				(font
					(size 0.7 0.7)
					(thickness 0.15)
				)
				(justify right top)
			)
		)
		(property "Datasheet" "https://media.digikey.com/pdf/Data%20Sheets/Lite-On%20PDFs/LTST-C190GKT.pdf"
			(at 0 0 90)
			(layer "F.Fab")
			(hide yes)
			(effects
				(font
					(size 1.27 1.27)
					(thickness 0.15)
				)
			)
		)
		(property "Description" "LED, Green, SMD, 0603, 20 mA, 2.1 V, 569 nm"
			(at 0 0 90)
			(layer "F.Fab")
			(hide yes)
			(effects
				(font
					(size 1.27 1.27)
					(thickness 0.15)
				)
			)
		)
		(property "MPN" "LTST-C190GKT"
			(at 0 0 270)
			(unlocked yes)
			(layer "F.Fab")
			(hide yes)
			(effects
				(font
					(size 1 1)
					(thickness 0.15)
				)
			)
		)
		(property "Manufacturer" "Lite-On"
			(at 0 0 270)
			(unlocked yes)
			(layer "F.Fab")
			(hide yes)
			(effects
				(font
					(size 1 1)
					(thickness 0.15)
				)
			)
		)
		(property "Author" "Antmicro"
			(at 0 0 270)
			(unlocked yes)
			(layer "F.Fab")
			(hide yes)
			(effects
				(font
					(size 1 1)
					(thickness 0.15)
				)
			)
		)
		(property "License" "Apache-2.0"
			(at 0 0 270)
			(unlocked yes)
			(layer "F.Fab")
			(hide yes)
			(effects
				(font
					(size 1 1)
					(thickness 0.15)
				)
			)
		)
		(property "Color" "Green"
			(at 0 0 270)
			(unlocked yes)
			(layer "F.Fab")
			(hide yes)
			(effects
				(font
					(size 1 1)
					(thickness 0.15)
				)
			)
		)
		(sheetname "/Power/")
		(sheetfile "power.kicad_sch")
		(attr smd)
		(fp_line
			(start 0.22 0.35)
			(end -0.22 0.35)
			(stroke
				(width 0.15)
				(type solid)
			)
			(layer "F.SilkS")
		)
		(fp_line
			(start -0.094672 0.201008)
			(end -0.094672 -0.198992)
			(stroke
				(width 0.1)
				(type solid)
			)
			(layer "F.SilkS")
		)
		(fp_line
			(start 0.105328 0.201008)
			(end -0.094672 0.001008)
			(stroke
				(width 0.1)
				(type solid)
			)
			(layer "F.SilkS")
		)
		(fp_line
			(start 0.105328 0.201008)
			(end 0.105328 -0.198992)
			(stroke
				(width 0.1)
				(type solid)
			)
			(layer "F.SilkS")
		)
		(fp_line
			(start -0.094672 0.001008)
			(end -0.24 0.001008)
			(stroke
				(width 0.1)
				(type solid)
			)
			(layer "F.SilkS")
		)
		(fp_line
			(start -0.094672 0.001008)
			(end 0.105328 -0.198992)
			(stroke
				(width 0.1)
				(type solid)
			)
			(layer "F.SilkS")
		)
		(fp_line
			(start 0.105328 0.001008)
			(end 0.24 0.001)
			(stroke
				(width 0.1)
				(type solid)
			)
			(layer "F.SilkS")
		)
		(fp_line
			(start -1.18 -0.319)
			(end -1.18 0.321)
			(stroke
				(width 0.15)
				(type solid)
			)
			(layer "F.SilkS")
		)
		(fp_line
			(start 0.22 -0.35)
			(end -0.22 -0.35)
			(stroke
				(width 0.15)
				(type solid)
			)
			(layer "F.SilkS")
		)
		(fp_rect
			(start 1.25 0.65)
			(end -1.25 -0.65)
			(stroke
				(width 0.05)
				(type solid)
			)
			(fill no)
			(layer "F.CrtYd")
		)
		(fp_line
			(start -0.199 0.2)
			(end -0.199 0.1)
			(stroke
				(width 0.15)
				(type solid)
			)
			(layer "F.Fab")
		)
		(fp_line
			(start 0.201 0.2)
			(end 0.201 0)
			(stroke
				(width 0.15)
				(type solid)
			)
			(layer "F.Fab")
		)
		(fp_line
			(start -0.199 0)
			(end -0.597 0)
			(stroke
				(width 0.15)
				(type solid)
			)
			(layer "F.Fab")
		)
		(fp_line
			(start -0.101 0)
			(end 0.201 0.2)
			(stroke
				(width 0.15)
				(type solid)
			)
			(layer "F.Fab")
		)
		(fp_line
			(start 0.201 0)
			(end 0.201 -0.202)
			(stroke
				(width 0.15)
				(type solid)
			)
			(layer "F.Fab")
		)
		(fp_line
			(start 0.599 0)
			(end 0.201 0)
			(stroke
				(width 0.15)
				(type solid)
			)
			(layer "F.Fab")
		)
		(fp_line
			(start -0.199 -0.202)
			(end -0.199 0.1)
			(stroke
				(width 0.15)
				(type solid)
			)
			(layer "F.Fab")
		)
		(fp_line
			(start 0.201 -0.202)
			(end -0.101 0)
			(stroke
				(width 0.15)
				(type solid)
			)
			(layer "F.Fab")
		)
		(fp_rect
			(start 0.848 0.4)
			(end -0.85 -0.402)
			(stroke
				(width 0.15)
				(type solid)
			)
			(fill no)
			(layer "F.Fab")
		)
		(fp_text user "Author: Antmicro"
			(at -1.4224 4.799 90)
			(layer "F.Fab")
			(effects
				(font
					(size 0.7 0.7)
					(thickness 0.15)
				)
				(justify right top)
			)
		)
		(fp_text user "${REFERENCE}"
			(at -1.4224 5.999 90)
			(layer "F.Fab")
			(effects
				(font
					(size 0.7 0.7)
					(thickness 0.15)
				)
				(justify right top)
			)
		)
		(fp_text user "License: Apache-2.0"
			(at -1.4224 3.599 90)
			(layer "F.Fab")
			(effects
				(font
					(size 0.7 0.7)
					(thickness 0.15)
				)
				(justify right top)
			)
		)
		(pad "1" smd roundrect
			(at -0.7 0 90)
			(size 0.8 1)
			(layers "F.Cu" "F.Mask" "F.Paste")
			(roundrect_rratio 0.2)
			(net 644 "Net-(D43-C)")
			(pinfunction "C")
			(pintype "passive")
		)
		(pad "2" smd roundrect
			(at 0.7 0 90)
			(size 0.8 1)
			(layers "F.Cu" "F.Mask" "F.Paste")
			(roundrect_rratio 0.2)
			(net 645 "Net-(D43-A)")
			(pinfunction "A")
			(pintype "passive")
		)
	)
	(footprint "antmicro-footprints:C_0402_1005Metric"
		(layer "F.Cu")
		(at 177.945 127.58 -90)
		(descr "Capacitor SMD 0402")
		(tags "capacitor SMD 0402")
		(property "Reference" "C49"
			(at -2.89 0.47 90)
			(layer "F.SilkS")
			(effects
				(font
					(size 0.7 0.7)
					(thickness 0.15)
				)
				(justify right top)
			)
		)
		(property "Value" "C_100n_0402"
			(at -1.022927 2.155213 90)
			(layer "F.Fab")
			(effects
				(font
					(size 0.7 0.7)
					(thickness 0.15)
				)
				(justify right top)
			)
		)
		(property "Datasheet" "https://www.murata.com/products/productdetail?partno=GRM155R61H104KE14%23"
			(at 0 0 90)
			(layer "F.Fab")
			(hide yes)
			(effects
				(font
					(size 1.27 1.27)
					(thickness 0.15)
				)
			)
		)
		(property "Description" "SMD Multilayer Ceramic Capacitor, 0.1 µF, 50 V, 0402 [1005 Metric], ± 10%, X5R, GRM Series"
			(at 0 0 90)
			(layer "F.Fab")
			(hide yes)
			(effects
				(font
					(size 1.27 1.27)
					(thickness 0.15)
				)
			)
		)
		(property "Manufacturer" "Murata"
			(at 0 0 270)
			(unlocked yes)
			(layer "F.Fab")
			(hide yes)
			(effects
				(font
					(size 1 1)
					(thickness 0.15)
				)
			)
		)
		(property "MPN" "GRM155R61H104KE14D"
			(at 0 0 270)
			(unlocked yes)
			(layer "F.Fab")
			(hide yes)
			(effects
				(font
					(size 1 1)
					(thickness 0.15)
				)
			)
		)
		(property "Val" "100n"
			(at 0 0 270)
			(unlocked yes)
			(layer "F.Fab")
			(hide yes)
			(effects
				(font
					(size 1 1)
					(thickness 0.15)
				)
			)
		)
		(property "License" "Apache-2.0"
			(at 0 0 270)
			(unlocked yes)
			(layer "F.Fab")
			(hide yes)
			(effects
				(font
					(size 1 1)
					(thickness 0.15)
				)
			)
		)
		(property "Author" "Antmicro"
			(at 0 0 270)
			(unlocked yes)
			(layer "F.Fab")
			(hide yes)
			(effects
				(font
					(size 1 1)
					(thickness 0.15)
				)
			)
		)
		(property "Voltage" "50V"
			(at 0 0 270)
			(unlocked yes)
			(layer "F.Fab")
			(hide yes)
			(effects
				(font
					(size 1 1)
					(thickness 0.15)
				)
			)
		)
		(property "Dielectric" "X5R"
			(at 0 0 270)
			(unlocked yes)
			(layer "F.Fab")
			(hide yes)
			(effects
				(font
					(size 1 1)
					(thickness 0.15)
				)
			)
		)
		(sheetname "/DCDC/")
		(sheetfile "dcdc.kicad_sch")
		(attr smd)
		(fp_rect
			(start -0.925 -0.47)
			(end 0.925 0.47)
			(stroke
				(width 0.05)
				(type default)
			)
			(fill no)
			(layer "F.CrtYd")
		)
		(fp_line
			(start -0.494 0.248)
			(end -0.494 -0.25)
			(stroke
				(width 0.15)
				(type solid)
			)
			(layer "F.Fab")
		)
		(fp_line
			(start 0.504 0.248)
			(end -0.494 0.248)
			(stroke
				(width 0.15)
				(type solid)
			)
			(layer "F.Fab")
		)
		(fp_line
			(start -0.494 -0.25)
			(end 0.504 -0.25)
			(stroke
				(width 0.15)
				(type solid)
			)
			(layer "F.Fab")
		)
		(fp_line
			(start 0.504 -0.25)
			(end 0.504 0.248)
			(stroke
				(width 0.15)
				(type solid)
			)
			(layer "F.Fab")
		)
		(fp_text user "License: Apache-2.0"
			(at -0.939 5.799 90)
			(layer "F.Fab")
			(effects
				(font
					(size 0.7 0.7)
					(thickness 0.15)
				)
				(justify right top)
			)
		)
		(fp_text user "${REFERENCE}"
			(at -0.939 4.599 90)
			(layer "F.Fab")
			(effects
				(font
					(size 0.7 0.7)
					(thickness 0.15)
				)
				(justify right top)
			)
		)
		(fp_text user "Author: Antmicro"
			(at -0.939 3.399 90)
			(layer "F.Fab")
			(effects
				(font
					(size 0.7 0.7)
					(thickness 0.15)
				)
				(justify right top)
			)
		)
		(pad "1" smd roundrect
			(at -0.48 0 270)
			(size 0.59 0.64)
			(layers "F.Cu" "F.Mask" "F.Paste")
			(roundrect_rratio 0.25)
			(net 13 "VCC")
			(pintype "passive")
		)
		(pad "2" smd roundrect
			(at 0.48 0 270)
			(size 0.59 0.64)
			(layers "F.Cu" "F.Mask" "F.Paste")
			(roundrect_rratio 0.25)
			(net 1 "GND")
			(pintype "passive")
		)
	)
	(footprint "antmicro-footprints:LED_0603_1608Metric_G"
		(layer "F.Cu")
		(at 235.540532 108.71 180)
		(descr "LED SMD 0603 Green")
		(tags "LED SMD 0603 Green")
		(property "Reference" "D51"
			(at -1.059468 -0.799999 0)
			(layer "F.SilkS")
			(effects
				(font
					(size 0.7 0.7)
					(thickness 0.15)
				)
				(justify right top)
			)
		)
		(property "Value" "LED_G_0603_LTST-C190GKT"
			(at -0.001 1.599 0)
			(layer "F.Fab")
			(effects
				(font
					(size 0.7 0.7)
					(thickness 0.15)
				)
				(justify right top)
			)
		)
		(property "Datasheet" "https://media.digikey.com/pdf/Data%20Sheets/Lite-On%20PDFs/LTST-C190GKT.pdf"
			(at 0 0 0)
			(layer "F.Fab")
			(hide yes)
			(effects
				(font
					(size 1.27 1.27)
					(thickness 0.15)
				)
			)
		)
		(property "Description" "LED, Green, SMD, 0603, 20 mA, 2.1 V, 569 nm"
			(at 0 0 0)
			(layer "F.Fab")
			(hide yes)
			(effects
				(font
					(size 1.27 1.27)
					(thickness 0.15)
				)
			)
		)
		(property "MPN" "LTST-C190GKT"
			(at 0 0 180)
			(unlocked yes)
			(layer "F.Fab")
			(hide yes)
			(effects
				(font
					(size 1 1)
					(thickness 0.15)
				)
			)
		)
		(property "Manufacturer" "Lite-On"
			(at 0 0 180)
			(unlocked yes)
			(layer "F.Fab")
			(hide yes)
			(effects
				(font
					(size 1 1)
					(thickness 0.15)
				)
			)
		)
		(property "Author" "Antmicro"
			(at 0 0 180)
			(unlocked yes)
			(layer "F.Fab")
			(hide yes)
			(effects
				(font
					(size 1 1)
					(thickness 0.15)
				)
			)
		)
		(property "License" "Apache-2.0"
			(at 0 0 180)
			(unlocked yes)
			(layer "F.Fab")
			(hide yes)
			(effects
				(font
					(size 1 1)
					(thickness 0.15)
				)
			)
		)
		(property "Color" "Green"
			(at 0 0 180)
			(unlocked yes)
			(layer "F.Fab")
			(hide yes)
			(effects
				(font
					(size 1 1)
					(thickness 0.15)
				)
			)
		)
		(sheetname "/Recovery USB/")
		(sheetfile "recovery_usb.kicad_sch")
		(attr smd)
		(fp_line
			(start 0.22 0.35)
			(end -0.22 0.35)
			(stroke
				(width 0.15)
				(type solid)
			)
			(layer "F.SilkS")
		)
		(fp_line
			(start 0.22 -0.35)
			(end -0.22 -0.35)
			(stroke
				(width 0.15)
				(type solid)
			)
			(layer "F.SilkS")
		)
		(fp_line
			(start 0.105328 0.201008)
			(end 0.105329 -0.198992)
			(stroke
				(width 0.1)
				(type solid)
			)
			(layer "F.SilkS")
		)
		(fp_line
			(start 0.105328 0.201008)
			(end -0.094672 0.001008)
			(stroke
				(width 0.1)
				(type solid)
			)
			(layer "F.SilkS")
		)
		(fp_line
			(start 0.105328 0.001008)
			(end 0.240001 0.001)
			(stroke
				(width 0.1)
				(type solid)
			)
			(layer "F.SilkS")
		)
		(fp_line
			(start -0.094672 0.201008)
			(end -0.094672 -0.198992)
			(stroke
				(width 0.1)
				(type solid)
			)
			(layer "F.SilkS")
		)
		(fp_line
			(start -0.094672 0.001008)
			(end 0.105329 -0.198992)
			(stroke
				(width 0.1)
				(type solid)
			)
			(layer "F.SilkS")
		)
		(fp_line
			(start -0.094672 0.001008)
			(end -0.24 0.001008)
			(stroke
				(width 0.1)
				(type solid)
			)
			(layer "F.SilkS")
		)
		(fp_line
			(start -1.18 -0.319)
			(end -1.18 0.321)
			(stroke
				(width 0.15)
				(type solid)
			)
			(layer "F.SilkS")
		)
		(fp_poly
			(pts
				(xy 1.25 0.65) (xy -1.25 0.65) (xy -1.25 -0.65) (xy 1.25 -0.65)
			)
			(stroke
				(width 0.05)
				(type solid)
			)
			(fill no)
			(layer "F.CrtYd")
		)
		(fp_line
			(start 0.599 0)
			(end 0.200999 0)
			(stroke
				(width 0.15)
				(type solid)
			)
			(layer "F.Fab")
		)
		(fp_line
			(start 0.201 0.2)
			(end 0.200999 0)
			(stroke
				(width 0.15)
				(type solid)
			)
			(layer "F.Fab")
		)
		(fp_line
			(start 0.201 -0.202)
			(end -0.101 0)
			(stroke
				(width 0.15)
				(type solid)
			)
			(layer "F.Fab")
		)
		(fp_line
			(start 0.200999 0)
			(end 0.201 -0.202)
			(stroke
				(width 0.15)
				(type solid)
			)
			(layer "F.Fab")
		)
		(fp_line
			(start -0.101 0)
			(end 0.201 0.2)
			(stroke
				(width 0.15)
				(type solid)
			)
			(layer "F.Fab")
		)
		(fp_line
			(start -0.199 0.2)
			(end -0.199 0.1)
			(stroke
				(width 0.15)
				(type solid)
			)
			(layer "F.Fab")
		)
		(fp_line
			(start -0.199 0)
			(end -0.597 0)
			(stroke
				(width 0.15)
				(type solid)
			)
			(layer "F.Fab")
		)
		(fp_line
			(start -0.199 -0.202)
			(end -0.199 0.1)
			(stroke
				(width 0.15)
				(type solid)
			)
			(layer "F.Fab")
		)
		(fp_poly
			(pts
				(xy 0.848 0.4) (xy -0.85 0.4) (xy -0.85 -0.402) (xy 0.848 -0.401999)
			)
			(stroke
				(width 0.15)
				(type solid)
			)
			(fill no)
			(layer "F.Fab")
		)
		(fp_text user "Author: Antmicro"
			(at -1.4224 4.799 0)
			(layer "F.Fab")
			(effects
				(font
					(size 0.7 0.7)
					(thickness 0.15)
				)
				(justify right top)
			)
		)
		(fp_text user "License: Apache-2.0"
			(at -1.4224 3.599 0)
			(layer "F.Fab")
			(effects
				(font
					(size 0.7 0.7)
					(thickness 0.15)
				)
				(justify right top)
			)
		)
		(fp_text user "${REFERENCE}"
			(at -1.4224 5.999 0)
			(layer "F.Fab")
			(effects
				(font
					(size 0.7 0.7)
					(thickness 0.15)
				)
				(justify right top)
			)
		)
		(pad "1" smd roundrect
			(at -0.7 0)
			(size 0.8 1)
			(layers "F.Cu" "F.Mask" "F.Paste")
			(roundrect_rratio 0.2)
			(net 1 "GND")
			(pinfunction "C")
			(pintype "passive")
		)
		(pad "2" smd roundrect
			(at 0.7 0)
			(size 0.8 1)
			(layers "F.Cu" "F.Mask" "F.Paste")
			(roundrect_rratio 0.2)
			(net 1391 "Net-(D51-A)")
			(pinfunction "A")
			(pintype "passive")
		)
	)
	(footprint "antmicro-footprints:C_0402_1005Metric"
		(layer "F.Cu")
		(at 179.152101 124.827356)
		(descr "Capacitor SMD 0402")
		(tags "capacitor SMD 0402")
		(property "Reference" "C60"
			(at -3.075 -0.23 0)
			(layer "F.SilkS")
			(effects
				(font
					(size 0.7 0.7)
					(thickness 0.15)
				)
				(justify left bottom)
			)
		)
		(property "Value" "C_100n_0402"
			(at -1.022927 2.155213 0)
			(layer "F.Fab")
			(effects
				(font
					(size 0.7 0.7)
					(thickness 0.15)
				)
				(justify left bottom)
			)
		)
		(property "Datasheet" "https://www.murata.com/products/productdetail?partno=GRM155R61H104KE14%23"
			(at 0 0 0)
			(layer "F.Fab")
			(hide yes)
			(effects
				(font
					(size 1.27 1.27)
					(thickness 0.15)
				)
			)
		)
		(property "Description" "SMD Multilayer Ceramic Capacitor, 0.1 µF, 50 V, 0402 [1005 Metric], ± 10%, X5R, GRM Series"
			(at 0 0 0)
			(layer "F.Fab")
			(hide yes)
			(effects
				(font
					(size 1.27 1.27)
					(thickness 0.15)
				)
			)
		)
		(property "Manufacturer" "Murata"
			(at 0 0 0)
			(unlocked yes)
			(layer "F.Fab")
			(hide yes)
			(effects
				(font
					(size 1 1)
					(thickness 0.15)
				)
			)
		)
		(property "MPN" "GRM155R61H104KE14D"
			(at 0 0 0)
			(unlocked yes)
			(layer "F.Fab")
			(hide yes)
			(effects
				(font
					(size 1 1)
					(thickness 0.15)
				)
			)
		)
		(property "Val" "100n"
			(at 0 0 0)
			(unlocked yes)
			(layer "F.Fab")
			(hide yes)
			(effects
				(font
					(size 1 1)
					(thickness 0.15)
				)
			)
		)
		(property "License" "Apache-2.0"
			(at 0 0 0)
			(unlocked yes)
			(layer "F.Fab")
			(hide yes)
			(effects
				(font
					(size 1 1)
					(thickness 0.15)
				)
			)
		)
		(property "Author" "Antmicro"
			(at 0 0 0)
			(unlocked yes)
			(layer "F.Fab")
			(hide yes)
			(effects
				(font
					(size 1 1)
					(thickness 0.15)
				)
			)
		)
		(property "Voltage" "50V"
			(at 0 0 0)
			(unlocked yes)
			(layer "F.Fab")
			(hide yes)
			(effects
				(font
					(size 1 1)
					(thickness 0.15)
				)
			)
		)
		(property "Dielectric" "X5R"
			(at 0 0 0)
			(unlocked yes)
			(layer "F.Fab")
			(hide yes)
			(effects
				(font
					(size 1 1)
					(thickness 0.15)
				)
			)
		)
		(sheetname "/DCDC/")
		(sheetfile "dcdc.kicad_sch")
		(attr smd)
		(fp_rect
			(start -0.925 -0.47)
			(end 0.925 0.47)
			(stroke
				(width 0.05)
				(type default)
			)
			(fill no)
			(layer "F.CrtYd")
		)
		(fp_line
			(start -0.494 -0.25)
			(end 0.504 -0.25)
			(stroke
				(width 0.15)
				(type solid)
			)
			(layer "F.Fab")
		)
		(fp_line
			(start -0.494 0.248)
			(end -0.494 -0.25)
			(stroke
				(width 0.15)
				(type solid)
			)
			(layer "F.Fab")
		)
		(fp_line
			(start 0.504 -0.25)
			(end 0.504 0.248)
			(stroke
				(width 0.15)
				(type solid)
			)
			(layer "F.Fab")
		)
		(fp_line
			(start 0.504 0.248)
			(end -0.494 0.248)
			(stroke
				(width 0.15)
				(type solid)
			)
			(layer "F.Fab")
		)
		(fp_text user "Author: Antmicro"
			(at -0.939 3.399 0)
			(layer "F.Fab")
			(effects
				(font
					(size 0.7 0.7)
					(thickness 0.15)
				)
				(justify left bottom)
			)
		)
		(fp_text user "License: Apache-2.0"
			(at -0.939 5.799 0)
			(layer "F.Fab")
			(effects
				(font
					(size 0.7 0.7)
					(thickness 0.15)
				)
				(justify left bottom)
			)
		)
		(fp_text user "${REFERENCE}"
			(at -0.939 4.599 0)
			(layer "F.Fab")
			(effects
				(font
					(size 0.7 0.7)
					(thickness 0.15)
				)
				(justify left bottom)
			)
		)
		(pad "1" smd roundrect
			(at -0.48 0)
			(size 0.59 0.64)
			(layers "F.Cu" "F.Mask" "F.Paste")
			(roundrect_rratio 0.25)
			(net 29 "/DCDC/3V3_PHASE")
			(pintype "passive")
		)
		(pad "2" smd roundrect
			(at 0.48 0)
			(size 0.59 0.64)
			(layers "F.Cu" "F.Mask" "F.Paste")
			(roundrect_rratio 0.25)
			(net 28 "/DCDC/3V3_BOOT")
			(pintype "passive")
		)
	)
)
